# BASEBOARD_FAB2 (Tioga Pass) — schematic netlist excerpt (pin names and nets, part order shuffled) for the footprints in the layout excerpt that follows; sources: Cadence DE-HDL packaged netlist, KiCad conversion of Wiwynn_Tioga_Pass_MB.brd

C8B11  CAP_A  22.0UF 4V 20% X6S  pkg 0603V  page 131 : A = P1V05_PCH_STBY ; B = GND
C2D47  CAP_A  22.0UF 4V 20% X6S  pkg 0603V  page 225 : A = PVDDQ_GHJ ; B = GND
R6D15  RES  240 1.0% EMPTY  pkg 0402  page 90 : A = PVCCIO_CPU0 ; B = PU_CPU0_SOCKET_ID_0

(kicad_pcb
	(version 20260206)
	(generator "pcbnew")
	(generator_version "10.0")
	(general
		(thickness 1.6)
		(legacy_teardrops no)
	)
	(paper "A4")
	(title_block
		(title "Wiwynn_Tioga_Pass_MB.brd")
		(comment 1 "Tioga Pass / footprints 1208-1210 of 4770")
	)
	(layers
		(0 "F.Cu" signal "TOP")
		(4 "In1.Cu" signal "L2GND")
		(6 "In2.Cu" signal "L3")
		(8 "In3.Cu" signal "L4GND")
		(10 "In4.Cu" signal "L5")
		(12 "In5.Cu" signal "L6GND")
		(14 "In6.Cu" signal "L7VCC")
		(16 "In7.Cu" signal "L8VCC")
		(18 "In8.Cu" signal "L9GND")
		(20 "In9.Cu" signal "L10")
		(22 "In10.Cu" signal "L11GND")
		(24 "In11.Cu" signal "L12")
		(26 "In12.Cu" signal "L13GND")
		(2 "B.Cu" signal "BOTTOM")
		(9 "F.Adhes" user "F.Adhesive")
		(11 "B.Adhes" user "B.Adhesive")
		(13 "F.Paste" user "Package Geometry/Pastemask Top")
		(15 "B.Paste" user "Package Geometry/Pastemask Bottom")
		(5 "F.SilkS" user "Ref Des/Silkscreen Top")
		(7 "B.SilkS" user "Ref Des/Silkscreen Bottom")
		(1 "F.Mask" user "Board Geometry/Soldermask Top")
		(3 "B.Mask" user "Board Geometry/Soldermask Bottom")
		(17 "Dwgs.User" user "User.Drawings")
		(19 "Cmts.User" user "User.Comments")
		(21 "Eco1.User" user "User.Eco1")
		(23 "Eco2.User" user "User.Eco2")
		(25 "Edge.Cuts" user "Board Geometry/Outline")
		(27 "Margin" user)
		(31 "F.CrtYd" user "Package Geometry/Place Bound Top")
		(29 "B.CrtYd" user "Package Geometry/Place Bound Bottom")
		(35 "F.Fab" user "Ref Des/Assembly Top")
		(33 "B.Fab" user "Ref Des/Assembly Bottom")
	)
	(footprint ""
		(layer "F.Cu")
		(at 105.889806 -68.365116 180)
		(property "Reference" "C2D47"
			(at 0 0 180)
			(layer "F.SilkS")
			(hide yes)
			(effects
				(font
					(size 1.27 1.27)
				)
			)
		)
		(property "Value" ""
			(at 0 0 180)
			(layer "F.Fab")
			(effects
				(font
					(size 1.27 1.27)
				)
			)
		)
		(duplicate_pad_numbers_are_jumpers no)
		(fp_poly
			(pts
				(xy -0.4953 -0.2032) (xy 0.4953 -0.2032) (xy 0.4953 1.6002) (xy -0.4953 1.6002)
			)
			(stroke
				(width 0)
				(type default)
			)
			(fill no)
			(layer "F.CrtYd")
		)
		(fp_line
			(start 0.4953 1.6002)
			(end -0.4953 1.6002)
			(stroke
				(width 0.1)
				(type default)
			)
			(layer "F.Fab")
		)
		(fp_line
			(start 0.4953 -0.2032)
			(end 0.4953 1.6002)
			(stroke
				(width 0.1)
				(type default)
			)
			(layer "F.Fab")
		)
		(fp_line
			(start -0.4953 1.6002)
			(end -0.4953 -0.2032)
			(stroke
				(width 0.1)
				(type default)
			)
			(layer "F.Fab")
		)
		(fp_line
			(start -0.4953 -0.2032)
			(end 0.4953 -0.2032)
			(stroke
				(width 0.1)
				(type default)
			)
			(layer "F.Fab")
		)
		(pad "1" smd rect
			(at 0 0 180)
			(size 0.762 0.889)
			(layers "F.Cu" "F.Mask" "F.Paste")
			(net "PVDDQ_GHJ")
		)
		(pad "2" smd rect
			(at 0 1.397 180)
			(size 0.762 0.889)
			(layers "F.Cu" "F.Mask" "F.Paste")
			(net "GND")
		)
		(zone
			(layer "F.Cu")
			(hatch none 0.5)
			(connect_pads
				(clearance 0)
			)
			(min_thickness 0.25)
			(keepout
				(tracks not_allowed)
				(vias allowed)
				(pads allowed)
				(copperpour not_allowed)
				(footprints allowed)
			)
			(placement
				(enabled no)
				(sheetname "")
			)
			(fill
				(thermal_gap 0.5)
				(thermal_bridge_width 0.5)
				(island_removal_mode 0)
			)
			(polygon
				(pts
					(xy 106.270806 -68.809616) (xy 105.508806 -68.809616) (xy 105.508806 -69.317616) (xy 106.270806 -69.317616)
				)
			)
		)
	)
	(footprint ""
		(layer "F.Cu")
		(at 277.241 -69.977)
		(property "Reference" "R6D15"
			(at 0 0 0)
			(layer "F.SilkS")
			(hide yes)
			(effects
				(font
					(size 1.27 1.27)
				)
			)
		)
		(property "Value" ""
			(at 0 0 0)
			(layer "F.Fab")
			(effects
				(font
					(size 1.27 1.27)
				)
			)
		)
		(duplicate_pad_numbers_are_jumpers no)
		(fp_poly
			(pts
				(xy -0.2794 -0.1016) (xy 0.2794 -0.1016) (xy 0.2794 0.9906) (xy -0.2794 0.9906)
			)
			(stroke
				(width 0)
				(type default)
			)
			(fill no)
			(layer "F.CrtYd")
		)
		(fp_line
			(start -0.2794 -0.1016)
			(end -0.2794 0.9906)
			(stroke
				(width 0.1)
				(type default)
			)
			(layer "F.Fab")
		)
		(fp_line
			(start -0.2794 0.9906)
			(end 0.2794 0.9906)
			(stroke
				(width 0.1)
				(type default)
			)
			(layer "F.Fab")
		)
		(fp_line
			(start 0.2794 -0.1016)
			(end -0.2794 -0.1016)
			(stroke
				(width 0.1)
				(type default)
			)
			(layer "F.Fab")
		)
		(fp_line
			(start 0.2794 0.9906)
			(end 0.2794 -0.1016)
			(stroke
				(width 0.1)
				(type default)
			)
			(layer "F.Fab")
		)
		(pad "1" smd rect
			(at 0 0)
			(size 0.508 0.508)
			(layers "F.Cu" "F.Mask" "F.Paste")
			(net "PVCCIO_CPU0")
		)
		(pad "2" smd rect
			(at 0 0.889)
			(size 0.508 0.508)
			(layers "F.Cu" "F.Mask" "F.Paste")
			(net "PU_CPU0_SOCKET_ID_0")
		)
		(zone
			(layer "F.Cu")
			(hatch none 0.5)
			(connect_pads
				(clearance 0)
			)
			(min_thickness 0.25)
			(keepout
				(tracks allowed)
				(vias not_allowed)
				(pads allowed)
				(copperpour not_allowed)
				(footprints allowed)
			)
			(placement
				(enabled no)
				(sheetname "")
			)
			(fill
				(thermal_gap 0.5)
				(thermal_bridge_width 0.5)
				(island_removal_mode 0)
			)
			(polygon
				(pts
					(xy 276.987 -69.723) (xy 277.495 -69.723) (xy 277.495 -69.342) (xy 276.987 -69.342)
				)
			)
		)
		(zone
			(layer "F.Cu")
			(hatch none 0.5)
			(connect_pads
				(clearance 0)
			)
			(min_thickness 0.25)
			(keepout
				(tracks not_allowed)
				(vias allowed)
				(pads allowed)
				(copperpour not_allowed)
				(footprints allowed)
			)
			(placement
				(enabled no)
				(sheetname "")
			)
			(fill
				(thermal_gap 0.5)
				(thermal_bridge_width 0.5)
				(island_removal_mode 0)
			)
			(polygon
				(pts
					(xy 276.987 -69.342) (xy 277.495 -69.342) (xy 277.495 -69.723) (xy 276.987 -69.723)
				)
			)
		)
	)
	(footprint ""
		(layer "F.Cu")
		(at 411.099 -127.5588 90)
		(property "Reference" "C8B11"
			(at 0 0 90)
			(layer "F.SilkS")
			(hide yes)
			(effects
				(font
					(size 1.27 1.27)
				)
			)
		)
		(property "Value" ""
			(at 0 0 90)
			(layer "F.Fab")
			(effects
				(font
					(size 1.27 1.27)
				)
			)
		)
		(duplicate_pad_numbers_are_jumpers no)
		(fp_poly
			(pts
				(xy -0.4953 -0.2032) (xy 0.4953 -0.2032) (xy 0.4953 1.6002) (xy -0.4953 1.6002)
			)
			(stroke
				(width 0)
				(type default)
			)
			(fill no)
			(layer "F.CrtYd")
		)
		(fp_line
			(start 0.4953 -0.2032)
			(end 0.4953 1.6002)
			(stroke
				(width 0.1)
				(type default)
			)
			(layer "F.Fab")
		)
		(fp_line
			(start -0.4953 -0.2032)
			(end 0.4953 -0.2032)
			(stroke
				(width 0.1)
				(type default)
			)
			(layer "F.Fab")
		)
		(fp_line
			(start 0.4953 1.6002)
			(end -0.4953 1.6002)
			(stroke
				(width 0.1)
				(type default)
			)
			(layer "F.Fab")
		)
		(fp_line
			(start -0.4953 1.6002)
			(end -0.4953 -0.2032)
			(stroke
				(width 0.1)
				(type default)
			)
			(layer "F.Fab")
		)
		(pad "1" smd rect
			(at 0 0 90)
			(size 0.762 0.889)
			(layers "F.Cu" "F.Mask" "F.Paste")
			(net "P1V05_PCH_STBY")
		)
		(pad "2" smd rect
			(at 0 1.397 90)
			(size 0.762 0.889)
			(layers "F.Cu" "F.Mask" "F.Paste")
			(net "GND")
		)
		(zone
			(layer "F.Cu")
			(hatch none 0.5)
			(connect_pads
				(clearance 0)
			)
			(min_thickness 0.25)
			(keepout
				(tracks not_allowed)
				(vias allowed)
				(pads allowed)
				(copperpour not_allowed)
				(footprints allowed)
			)
			(placement
				(enabled no)
				(sheetname "")
			)
			(fill
				(thermal_gap 0.5)
				(thermal_bridge_width 0.5)
				(island_removal_mode 0)
			)
			(polygon
				(pts
					(xy 411.5435 -127.1778) (xy 411.5435 -127.9398) (xy 412.0515 -127.9398) (xy 412.0515 -127.1778)
				)
			)
		)
	)
)
